# T6G (Grand Teton) — schematic netlist excerpt (pin names and nets, part order shuffled) for the footprints in the layout excerpt that follows; sources: Cadence DE-HDL packaged netlist, KiCad conversion of 04192023_DAF0TMB3IC0_F0TG_MB_C_brd_V02_OCP.brd

C817  Q_CAP_DIFFBUS  DIFF BUS_0.22UF 6.3V 20% X6S  pkg C0201  page 65 : \1\ = P5E_CPU1_P0_TX_C_DP<10> ; \2\ = P5E_CPU1_P0_TX_DP<10>
R856  Q_RES  0 5% CHIP  pkg 0402LF  page 81 : A = FM_HDT_HDR_RESET_N ; B = HDT_HDR_RESET_N

U224  74LVC1G126SE7  74LVC1G126SE-7 IC  pkg SOT353_0-65_2X1-25  page 132
  OE  = OCP_SFF_AUX_PWR_EN_R2
  A  = RST_SMB_SWITCH_N
  GND  = GND
  Y  = RST_HP_OCP_SFF_R_N
  VCC  = P3V3_AUX

(kicad_pcb
	(version 20260206)
	(generator "pcbnew")
	(generator_version "10.0")
	(general
		(thickness 1.6)
		(legacy_teardrops no)
	)
	(paper "A4")
	(title_block
		(title "04192023_DAF0TMB3IC0_F0TG_MB_C_brd_V02_OCP.brd")
		(comment 1 "Grand Teton / footprints 4288-4290 of 8354")
	)
	(layers
		(0 "F.Cu" signal "TOP")
		(4 "In1.Cu" signal "GND")
		(6 "In2.Cu" signal "IN1")
		(8 "In3.Cu" signal "GND1")
		(10 "In4.Cu" signal "IN2")
		(12 "In5.Cu" signal "GND2")
		(14 "In6.Cu" signal "IN3")
		(16 "In7.Cu" signal "GND3")
		(18 "In8.Cu" signal "VCC")
		(20 "In9.Cu" signal "VCC1")
		(22 "In10.Cu" signal "GND4")
		(24 "In11.Cu" signal "IN4")
		(26 "In12.Cu" signal "GND5")
		(28 "In13.Cu" signal "IN5")
		(30 "In14.Cu" signal "GND6")
		(32 "In15.Cu" signal "IN6")
		(34 "In16.Cu" signal "GND7")
		(2 "B.Cu" signal "BOTTOM")
		(9 "F.Adhes" user "F.Adhesive")
		(11 "B.Adhes" user "B.Adhesive")
		(13 "F.Paste" user "Package Geometry/Pastemask Top")
		(15 "B.Paste" user "Package Geometry/Pastemask Bottom")
		(5 "F.SilkS" user "Ref Des/Silkscreen Top")
		(7 "B.SilkS" user "Ref Des/Silkscreen Bottom")
		(1 "F.Mask" user "Board Geometry/Soldermask Top")
		(3 "B.Mask" user "Board Geometry/Soldermask Bottom")
		(17 "Dwgs.User" user "User.Drawings")
		(19 "Cmts.User" user "User.Comments")
		(21 "Eco1.User" user "User.Eco1")
		(23 "Eco2.User" user "User.Eco2")
		(25 "Edge.Cuts" user "Board Geometry/Outline")
		(27 "Margin" user)
		(31 "F.CrtYd" user "Package Geometry/Place Bound Top")
		(29 "B.CrtYd" user "Package Geometry/Place Bound Bottom")
		(35 "F.Fab" user "Ref Des/Assembly Top")
		(33 "B.Fab" user "Ref Des/Assembly Bottom")
	)
	(footprint ""
		(layer "F.Cu")
		(at 459.437486 -93.627448)
		(property "Reference" "U224"
			(at -1.651 -1.793748 0)
			(unlocked yes)
			(layer "F.SilkS")
			(effects
				(font
					(size 0.7874 0.5842)
					(thickness 0.1524)
				)
				(justify left)
			)
		)
		(property "Value" ""
			(at 0 0 0)
			(layer "F.Fab")
			(effects
				(font
					(size 1.27 1.27)
				)
			)
		)
		(duplicate_pad_numbers_are_jumpers no)
		(fp_line
			(start -1.400048 1.100074)
			(end -1.400048 -1.100074)
			(stroke
				(width 0.1524)
				(type default)
			)
			(layer "F.SilkS")
		)
		(fp_line
			(start 1.400048 -1.100074)
			(end -1.400048 -1.100074)
			(stroke
				(width 0.1524)
				(type default)
			)
			(layer "F.SilkS")
		)
		(fp_line
			(start 1.400048 -1.100074)
			(end 1.400048 1.100074)
			(stroke
				(width 0.1524)
				(type default)
			)
			(layer "F.SilkS")
		)
		(fp_line
			(start 1.400048 1.100074)
			(end -1.400048 1.100074)
			(stroke
				(width 0.1524)
				(type default)
			)
			(layer "F.SilkS")
		)
		(fp_poly
			(pts
				(xy -2.606548 -0.141986) (xy -2.606548 -1.157986) (xy -1.590548 -0.649986)
			)
			(stroke
				(width 0)
				(type default)
			)
			(fill yes)
			(layer "F.SilkS")
		)
		(fp_line
			(start -0.674878 -1.100074)
			(end 0.674878 -1.100074)
			(stroke
				(width 0.1)
				(type default)
			)
			(layer "F.Fab")
		)
		(fp_line
			(start -0.674878 1.100074)
			(end -0.674878 -1.100074)
			(stroke
				(width 0.1)
				(type default)
			)
			(layer "F.Fab")
		)
		(fp_line
			(start 0.674878 -1.100074)
			(end 0.674878 1.100074)
			(stroke
				(width 0.1)
				(type default)
			)
			(layer "F.Fab")
		)
		(fp_line
			(start 0.674878 1.100074)
			(end -0.674878 1.100074)
			(stroke
				(width 0.1)
				(type default)
			)
			(layer "F.Fab")
		)
		(fp_poly
			(pts
				(xy -1.590548 -0.649986) (xy -2.606548 -1.157986) (xy -2.606548 -0.141986)
			)
			(stroke
				(width 0)
				(type default)
			)
			(fill yes)
			(layer "F.Fab")
		)
		(pad "1" smd rect
			(at -0.94996 -0.649986 270)
			(size 0.4318 0.6096)
			(layers "F.Cu" "F.Mask" "F.Paste")
			(net "OCP_SFF_AUX_PWR_EN_R2")
		)
		(pad "2" smd rect
			(at -0.94996 0 270)
			(size 0.4318 0.6096)
			(layers "F.Cu" "F.Mask" "F.Paste")
			(net "RST_SMB_SWITCH_N")
		)
		(pad "3" smd rect
			(at -0.94996 0.649986 270)
			(size 0.4318 0.6096)
			(layers "F.Cu" "F.Mask" "F.Paste")
			(net "GND")
		)
		(pad "4" smd rect
			(at 0.94996 0.649986 270)
			(size 0.4318 0.6096)
			(layers "F.Cu" "F.Mask" "F.Paste")
			(net "RST_HP_OCP_SFF_R_N")
		)
		(pad "5" smd rect
			(at 0.94996 -0.649986 270)
			(size 0.4318 0.6096)
			(layers "F.Cu" "F.Mask" "F.Paste")
			(net "P3V3_AUX")
		)
	)
	(footprint ""
		(layer "F.Cu")
		(at 61.709554 -375.49963 -90)
		(property "Reference" "C817"
			(at 0 0 270)
			(layer "F.SilkS")
			(hide yes)
			(effects
				(font
					(size 1.27 1.27)
				)
			)
		)
		(property "Value" ""
			(at 0 0 270)
			(layer "F.Fab")
			(effects
				(font
					(size 1.27 1.27)
				)
			)
		)
		(duplicate_pad_numbers_are_jumpers no)
		(fp_line
			(start -0.299974 0.150114)
			(end -0.299974 -0.150114)
			(stroke
				(width 0.1)
				(type default)
			)
			(layer "F.Fab")
		)
		(fp_line
			(start 0.299974 0.150114)
			(end -0.299974 0.150114)
			(stroke
				(width 0.1)
				(type default)
			)
			(layer "F.Fab")
		)
		(fp_line
			(start -0.299974 -0.150114)
			(end 0.299974 -0.150114)
			(stroke
				(width 0.1)
				(type default)
			)
			(layer "F.Fab")
		)
		(fp_line
			(start 0.299974 -0.150114)
			(end 0.299974 0.150114)
			(stroke
				(width 0.1)
				(type default)
			)
			(layer "F.Fab")
		)
		(pad "1" smd rect
			(at -0.2667 0 270)
			(size 0.3048 0.381)
			(layers "F.Cu" "F.Mask" "F.Paste")
			(net "P5E_CPU1_P0_TX_C_DP<10>")
		)
		(pad "2" smd rect
			(at 0.2667 0 270)
			(size 0.3048 0.381)
			(layers "F.Cu" "F.Mask" "F.Paste")
			(net "P5E_CPU1_P0_TX_DP<10>")
		)
	)
	(footprint ""
		(layer "F.Cu")
		(at 189.103 -133.568948 90)
		(property "Reference" "R856"
			(at 0 0 90)
			(layer "F.SilkS")
			(hide yes)
			(effects
				(font
					(size 1.27 1.27)
				)
			)
		)
		(property "Value" ""
			(at 0 0 90)
			(layer "F.Fab")
			(effects
				(font
					(size 1.27 1.27)
				)
			)
		)
		(duplicate_pad_numbers_are_jumpers no)
		(fp_line
			(start 0.7874 -0.4064)
			(end 0.7874 0.4064)
			(stroke
				(width 0.1524)
				(type default)
			)
			(layer "F.SilkS")
		)
		(fp_line
			(start -0.7874 -0.4064)
			(end 0.7874 -0.4064)
			(stroke
				(width 0.1524)
				(type default)
			)
			(layer "F.SilkS")
		)
		(fp_line
			(start 0.7874 0.4064)
			(end -0.7874 0.4064)
			(stroke
				(width 0.1524)
				(type default)
			)
			(layer "F.SilkS")
		)
		(fp_line
			(start -0.7874 0.4064)
			(end -0.7874 -0.4064)
			(stroke
				(width 0.1524)
				(type default)
			)
			(layer "F.SilkS")
		)
		(fp_line
			(start -0.12065 -0.305054)
			(end -0.12065 -0.2794)
			(stroke
				(width 0.1)
				(type default)
			)
			(layer "F.Fab")
		)
		(fp_line
			(start -0.67945 -0.305054)
			(end -0.12065 -0.305054)
			(stroke
				(width 0.1)
				(type default)
			)
			(layer "F.Fab")
		)
		(fp_line
			(start 0.67945 -0.3048)
			(end 0.67945 0.3048)
			(stroke
				(width 0.1)
				(type default)
			)
			(layer "F.Fab")
		)
		(fp_line
			(start 0.12065 -0.3048)
			(end 0.67945 -0.3048)
			(stroke
				(width 0.1)
				(type default)
			)
			(layer "F.Fab")
		)
		(fp_line
			(start 0.12065 -0.2794)
			(end 0.12065 -0.3048)
			(stroke
				(width 0.1)
				(type default)
			)
			(layer "F.Fab")
		)
		(fp_line
			(start -0.12065 -0.2794)
			(end 0.12065 -0.2794)
			(stroke
				(width 0.1)
				(type default)
			)
			(layer "F.Fab")
		)
		(fp_line
			(start 0.120396 0.2794)
			(end -0.12065 0.2794)
			(stroke
				(width 0.1)
				(type default)
			)
			(layer "F.Fab")
		)
		(fp_line
			(start -0.12065 0.2794)
			(end -0.12065 0.3048)
			(stroke
				(width 0.1)
				(type default)
			)
			(layer "F.Fab")
		)
		(fp_line
			(start 0.67945 0.3048)
			(end 0.120396 0.3048)
			(stroke
				(width 0.1)
				(type default)
			)
			(layer "F.Fab")
		)
		(fp_line
			(start 0.120396 0.3048)
			(end 0.120396 0.2794)
			(stroke
				(width 0.1)
				(type default)
			)
			(layer "F.Fab")
		)
		(fp_line
			(start -0.12065 0.3048)
			(end -0.67945 0.3048)
			(stroke
				(width 0.1)
				(type default)
			)
			(layer "F.Fab")
		)
		(fp_line
			(start -0.67945 0.3048)
			(end -0.67945 -0.305054)
			(stroke
				(width 0.1)
				(type default)
			)
			(layer "F.Fab")
		)
		(pad "1" smd circle
			(at -0.40005 0 90)
			(size 0 0)
			(layers "F.Cu" "F.Mask" "F.Paste")
			(net "FM_HDT_HDR_RESET_N")
		)
		(pad "2" smd circle
			(at 0.40005 0 90)
			(size 0 0)
			(layers "F.Cu" "F.Mask" "F.Paste")
			(net "HDT_HDR_RESET_N")
		)
	)
)
